FILE_TYPE = CONNECTIVITY;
{Allegro Design Entry HDL 17.4-2019 S026 (4007227) 1/17/2022}
"PAGE_NUMBER" = 16;
0"NC";
1"M_G_CPU0_SA_DQ<31:0>";
2"M_G_CPU0_SB_DQ<31:0>";
3"M_G_CPU0_SA_CB<7:0>";
4"M_G_CPU0_SB_CB<7:0>";
5"M_G_CPU0_SA_DQS_DN<9:0>";
6"M_G_CPU0_SA_DQS_DP<9:0>";
7"M_G_CPU0_SB_DQS_DP<9:0>";
8"M_G_CPU0_SB_DQS_DN<9:0>";
9"M_G_CPU0_SA_CA<6:0>";
10"M_G_CPU0_SB_CA<6:0>";
11"M_G_CPU0_ALERT_N";
12"M_G_CPU0_ALERT_R_N";
13"TP_M_G_CPU0_SA_TEST39G";
14"M_G_CPU0_CLK_DN<0>";
15"M_G_CPU0_CLK_DP<0>";
16"M_G_CPU0_SA_CS_N<1>";
17"M_G_CPU0_SA_CS_N<0>";
18"M_G_CPU0_SA_PAR";
19"M_G_CPU0_SA_RSP<0>";
20"M_G_CPU0_SB_RSP<0>";
21"M_G_CPU0_SB_CS_N<0>";
22"M_G_CPU0_SB_CS_N<1>";
23"M_G_CPU0_SB_PAR";
24"M_G_CPU0_RESET_N";
25"M_G_CPU0_SB_CA<6>";
26"M_G_CPU0_SA_CA<6>";
27"M_G_CPU0_SB_CA<5>";
28"M_G_CPU0_SA_CA<5>";
29"M_G_CPU0_SB_CA<4>";
30"M_G_CPU0_SA_CA<4>";
31"M_G_CPU0_SB_CA<3>";
32"M_G_CPU0_SA_CA<3>";
33"M_G_CPU0_SB_CA<2>";
34"M_G_CPU0_SA_CA<2>";
35"M_G_CPU0_SB_CA<1>";
36"M_G_CPU0_SA_CA<1>";
37"M_G_CPU0_SB_CA<0>";
38"M_G_CPU0_SA_CA<0>";
39"M_G_CPU0_SB_DQS_DN<9>";
40"M_G_CPU0_SB_DQS_DP<9>";
41"M_G_CPU0_SB_DQS_DP<4>";
42"M_G_CPU0_SB_DQS_DN<8>";
43"M_G_CPU0_SB_DQS_DP<3>";
44"M_G_CPU0_SB_DQS_DN<7>";
45"M_G_CPU0_SB_DQS_DP<2>";
46"M_G_CPU0_SB_DQS_DN<6>";
47"M_G_CPU0_SB_DQS_DP<1>";
48"M_G_CPU0_SB_DQS_DN<5>";
49"M_G_CPU0_SB_DQS_DP<0>";
50"M_G_CPU0_SB_DQS_DN<4>";
51"M_G_CPU0_SA_DQS_DN<9>";
52"M_G_CPU0_SB_DQS_DN<3>";
53"M_G_CPU0_SB_DQS_DN<2>";
54"M_G_CPU0_SB_DQS_DN<1>";
55"M_G_CPU0_SB_DQS_DN<0>";
56"M_G_CPU0_SB_DQS_DP<8>";
57"M_G_CPU0_SB_DQS_DP<7>";
58"M_G_CPU0_SB_DQS_DP<6>";
59"M_G_CPU0_SB_DQS_DP<5>";
60"M_G_CPU0_SA_DQS_DP<9>";
61"M_G_CPU0_SA_DQS_DP<8>";
62"M_G_CPU0_SA_DQS_DP<7>";
63"M_G_CPU0_SA_DQS_DP<6>";
64"M_G_CPU0_SA_DQS_DP<5>";
65"M_G_CPU0_SA_DQS_DP<4>";
66"M_G_CPU0_SA_DQS_DN<8>";
67"M_G_CPU0_SA_DQS_DP<3>";
68"M_G_CPU0_SA_DQS_DN<7>";
69"M_G_CPU0_SA_DQS_DP<2>";
70"M_G_CPU0_SA_DQS_DN<6>";
71"M_G_CPU0_SA_DQS_DP<1>";
72"M_G_CPU0_SA_DQS_DN<5>";
73"M_G_CPU0_SA_DQS_DP<0>";
74"M_G_CPU0_SA_DQS_DN<4>";
75"M_G_CPU0_SA_DQS_DN<3>";
76"M_G_CPU0_SA_DQS_DN<2>";
77"M_G_CPU0_SA_DQS_DN<1>";
78"M_G_CPU0_SA_DQS_DN<0>";
79"M_G_CPU0_SB_CB<7>";
80"M_G_CPU0_SB_CB<6>";
81"M_G_CPU0_SB_CB<5>";
82"M_G_CPU0_SB_CB<4>";
83"M_G_CPU0_SB_CB<3>";
84"M_G_CPU0_SB_CB<2>";
85"M_G_CPU0_SB_CB<1>";
86"M_G_CPU0_SB_CB<0>";
87"M_G_CPU0_SA_CB<1>";
88"M_G_CPU0_SA_CB<0>";
89"M_G_CPU0_SB_DQ<29>";
90"M_G_CPU0_SB_DQ<28>";
91"M_G_CPU0_SB_DQ<27>";
92"M_G_CPU0_SB_DQ<26>";
93"M_G_CPU0_SB_DQ<25>";
94"M_G_CPU0_SB_DQ<24>";
95"M_G_CPU0_SB_DQ<23>";
96"M_G_CPU0_SB_DQ<22>";
97"M_G_CPU0_SA_CB<7>";
98"M_G_CPU0_SA_CB<6>";
99"M_G_CPU0_SB_DQ<31>";
100"M_G_CPU0_SA_CB<5>";
101"M_G_CPU0_SB_DQ<30>";
102"M_G_CPU0_SA_CB<4>";
103"M_G_CPU0_SA_CB<3>";
104"M_G_CPU0_SA_CB<2>";
105"M_G_CPU0_SB_DQ<19>";
106"M_G_CPU0_SB_DQ<18>";
107"M_G_CPU0_SB_DQ<17>";
108"M_G_CPU0_SB_DQ<16>";
109"M_G_CPU0_SB_DQ<15>";
110"M_G_CPU0_SB_DQ<14>";
111"M_G_CPU0_SB_DQ<9>";
112"M_G_CPU0_SB_DQ<13>";
113"M_G_CPU0_SB_DQ<8>";
114"M_G_CPU0_SB_DQ<12>";
115"M_G_CPU0_SB_DQ<7>";
116"M_G_CPU0_SB_DQ<11>";
117"M_G_CPU0_SB_DQ<6>";
118"M_G_CPU0_SB_DQ<10>";
119"M_G_CPU0_SB_DQ<21>";
120"M_G_CPU0_SB_DQ<5>";
121"M_G_CPU0_SB_DQ<20>";
122"M_G_CPU0_SB_DQ<4>";
123"M_G_CPU0_SA_DQ<21>";
124"M_G_CPU0_SB_DQ<0>";
125"M_G_CPU0_SA_DQ<20>";
126"M_G_CPU0_SA_DQ<31>";
127"M_G_CPU0_SA_DQ<30>";
128"M_G_CPU0_SA_DQ<19>";
129"M_G_CPU0_SA_DQ<18>";
130"M_G_CPU0_SA_DQ<29>";
131"M_G_CPU0_SA_DQ<17>";
132"M_G_CPU0_SA_DQ<28>";
133"M_G_CPU0_SA_DQ<27>";
134"M_G_CPU0_SA_DQ<26>";
135"M_G_CPU0_SA_DQ<25>";
136"M_G_CPU0_SA_DQ<24>";
137"M_G_CPU0_SB_DQ<3>";
138"M_G_CPU0_SA_DQ<23>";
139"M_G_CPU0_SB_DQ<2>";
140"M_G_CPU0_SA_DQ<22>";
141"M_G_CPU0_SB_DQ<1>";
142"M_G_CPU0_SA_DQ<0>";
143"M_G_CPU0_SA_DQ<10>";
144"M_G_CPU0_SA_DQ<9>";
145"M_G_CPU0_SA_DQ<8>";
146"M_G_CPU0_SA_DQ<7>";
147"M_G_CPU0_SA_DQ<6>";
148"M_G_CPU0_SA_DQ<16>";
149"M_G_CPU0_SA_DQ<5>";
150"M_G_CPU0_SA_DQ<15>";
151"M_G_CPU0_SA_DQ<4>";
152"M_G_CPU0_SA_DQ<14>";
153"M_G_CPU0_SA_DQ<3>";
154"M_G_CPU0_SA_DQ<13>";
155"M_G_CPU0_SA_DQ<2>";
156"M_G_CPU0_SA_DQ<12>";
157"M_G_CPU0_SA_DQ<1>";
158"M_G_CPU0_SA_DQ<11>";
%"GENOA_SP5"
"7","(-4700,3675)","0","pure_quanta","I167";
;
LOCATION"U25"
$SEC"7"
CDS_SEC"7"
PART_TYPE"SMLF"
MATERIAL"IO"
VALUE"SOCKET6096_13568-001"
CDS_LIB"pure_quanta"
CDS_LMAN_SYM_OUTLINE"-650,2525,650,-2525"
NEEDS_NO_SIZE"TRUE"
PART_NUMBER"DGA^6000030";
"TEST39G"
$PN"BF4"13;
"MG1_CLK_L"
$PN"BG2"0;
"MG1_CLK_H"
$PN"BF2"0;
"MG0_CLK_L"
$PN"BD2"14;
"MG0_CLK_H"
$PN"BC2"15;
"MGA_PAR"
$PN"BC3"18;
"MGB_DQS_H9"
$PN"BV2"40;
"MGB_PAR"
$PN"BL3"23;
"MGA_CHECK1"
$PN"AK4"87;
"MGA_DATA0"
$PN"E2"142;
"MGA_DATA10"
$PN"M2"143;
"MGA_DATA21"
$PN"AB4"123;
"MGB_DATA0"
$PN"CB2"124;
"MGB_DQS_H4"
$PN"BY4"41;
"MGB_DQS_L8"
$PN"DC3"42;
"MGA_CHECK0"
$PN"AJ2"88;
"MGA_DATA20"
$PN"AA2"125;
"MGA_DATA31"
$PN"AJ3"126;
"MGA_DQS_H9"
$PN"AN3"60;
"MGB_DQS_H3"
$PN"DB2"43;
"MGB_DQS_L7"
$PN"CU3"44;
"MGA0_CS_L1"
$PN"AV4"16;
"MGA1_CS_L1"
$PN"AW3"0;
"MGA_DATA30"
$PN"AH2"127;
"MGA_DQS_H8"
$PN"AG3"61;
"MGB_DATA19"
$PN"CT4"105;
"MGB_DQS_H2"
$PN"CT2"45;
"MGB_DQS_L6"
$PN"CL3"46;
"MGA0_CS_L0"
$PN"AU2"17;
"MGA1_CS_L0"
$PN"AV2"0;
"MGA_DQS_H7"
$PN"AA3"62;
"MGB_DATA18"
$PN"CR2"106;
"MGB_DATA29"
$PN"DE3"89;
"MGB_DQS_H1"
$PN"CK2"47;
"MGB_DQS_L5"
$PN"CE3"48;
"MGA_DQS_H6"
$PN"R3"63;
"MGB_DATA17"
$PN"CR3"107;
"MGB_DATA28"
$PN"DD2"90;
"MGB_DQS_H0"
$PN"CD2"49;
"MGB_DQS_L4"
$PN"BW3"50;
"MGA_DQS_H5"
$PN"J3"64;
"MGA_DQS_L9"
$PN"AM4"51;
"MGB0_RSP_L"
$PN"BP2"20;
"MGB1_RSP_L"
$PN"BR2"0;
"MGB_CHECK7"
$PN"BV4"79;
"MGB_DATA16"
$PN"CP2"108;
"MGB_DATA27"
$PN"DB4"91;
"MGB_DQS_L3"
$PN"DC2"52;
"MGA_DQS_H4"
$PN"AL2"65;
"MGA_DQS_L8"
$PN"AF4"66;
"MGB_CA6"
$PN"BK2"25;
"MGB_CHECK6"
$PN"BU2"80;
"MGB_DATA15"
$PN"CP4"109;
"MGB_DATA26"
$PN"DA2"92;
"MGB_DQS_L2"
$PN"CU2"53;
"MGA_CA6"
$PN"BB4"26;
"MGA_DQS_H3"
$PN"AE2"67;
"MGA_DQS_L7"
$PN"Y4"68;
"MGB_CA5"
$PN"BK4"27;
"MGB_CHECK5"
$PN"BU3"81;
"MGB_DATA14"
$PN"CN2"110;
"MGB_DATA25"
$PN"DA3"93;
"MGB_DQS_L1"
$PN"CL2"54;
"MGA_CA5"
$PN"BB2"28;
"MGA_DATA9"
$PN"M4"144;
"MGA_DATA19"
$PN"W3"128;
"MGA_DQS_H2"
$PN"W2"69;
"MGA_DQS_L6"
$PN"P4"70;
"MGB_CA4"
$PN"BJ3"29;
"MGB_CHECK4"
$PN"BT2"82;
"MGB_DATA9"
$PN"CJ3"111;
"MGB_DATA13"
$PN"CN3"112;
"MGB_DATA24"
$PN"CY2"94;
"MGB_DQS_L0"
$PN"CE2"55;
"MGA_CA4"
$PN"BA2"30;
"MGA_DATA8"
$PN"L2"145;
"MGA_DATA18"
$PN"V2"129;
"MGA_DATA29"
$PN"AH4"130;
"MGA_DQS_H1"
$PN"N2"71;
"MGA_DQS_L5"
$PN"H4"72;
"MGB_CA3"
$PN"BJ2"31;
"MGB_CHECK3"
$PN"CB4"83;
"MGB_DATA8"
$PN"CH2"113;
"MGB_DATA12"
$PN"CM2"114;
"MGB_DATA23"
$PN"CY4"95;
"MGA_CA3"
$PN"BA3"32;
"MGA_DATA7"
$PN"L3"146;
"MGA_DATA17"
$PN"V4"131;
"MGA_DATA28"
$PN"AG2"132;
"MGA_DQS_H0"
$PN"G2"73;
"MGA_DQS_L4"
$PN"AM2"74;
"MGB_CA2"
$PN"BH2"33;
"MGB_CHECK2"
$PN"CA2"84;
"MGB_DATA7"
$PN"CH4"115;
"MGB_DATA11"
$PN"CK4"116;
"MGB_DATA22"
$PN"CW2"96;
"MGA0_RSP_L"
$PN"BN3"19;
"MGA1_RSP_L"
$PN"BP4"0;
"MGA_CA2"
$PN"AY4"34;
"MGA_CHECK7"
$PN"AR3"97;
"MGA_DATA6"
$PN"K2"147;
"MGA_DATA16"
$PN"U2"148;
"MGA_DATA27"
$PN"AE3"133;
"MGA_DQS_L3"
$PN"AF2"75;
"MGB_CA1"
$PN"BH4"35;
"MGB_CHECK1"
$PN"CA3"85;
"MGB_DATA6"
$PN"CG2"117;
"MGB_DATA10"
$PN"CJ2"118;
"MGB_DATA21"
$PN"CW3"119;
"MGA_CA1"
$PN"AY2"36;
"MGA_CHECK6"
$PN"AP2"98;
"MGA_DATA5"
$PN"K4"149;
"MGA_DATA15"
$PN"U3"150;
"MGA_DATA26"
$PN"AD2"134;
"MGA_DQS_L2"
$PN"Y2"76;
"MGB_CA0"
$PN"BG3"37;
"MGB_CHECK0"
$PN"BY2"86;
"MGB_DATA5"
$PN"CG3"120;
"MGB_DATA20"
$PN"CV2"121;
"MGB_DATA31"
$PN"DF2"99;
"MGA_CA0"
$PN"AW2"38;
"MGA_CHECK5"
$PN"AP4"100;
"MGA_DATA4"
$PN"J2"151;
"MGA_DATA14"
$PN"T2"152;
"MGA_DATA25"
$PN"AD4"135;
"MGA_DQS_L1"
$PN"P2"77;
"MGB0_CS_L1"
$PN"BN2"22;
"MGB1_CS_L1"
$PN"BM2"0;
"MGB_DATA4"
$PN"CF2"122;
"MGB_DATA30"
$PN"DE2"101;
"MGB_DQS_H8"
$PN"DD4"56;
"MGA_CHECK4"
$PN"AN2"102;
"MGA_DATA3"
$PN"G3"153;
"MGA_DATA13"
$PN"T4"154;
"MGA_DATA24"
$PN"AC2"136;
"MGA_DQS_L0"
$PN"H2"78;
"MGB0_CS_L0"
$PN"BM4"21;
"MGB1_CS_L0"
$PN"BL2"0;
"MGB_DATA3"
$PN"CD4"137;
"MGB_DQS_H7"
$PN"CV4"57;
"MGA_CHECK3"
$PN"AL3"103;
"MGA_DATA2"
$PN"F2"155;
"MGA_DATA12"
$PN"R2"156;
"MGA_DATA23"
$PN"AC3"138;
"MGB_DATA2"
$PN"CC2"139;
"MGB_DQS_H6"
$PN"CM4"58;
"MGA_CHECK2"
$PN"AK2"104;
"MGA_DATA1"
$PN"F4"157;
"MGA_DATA11"
$PN"N3"158;
"MGA_DATA22"
$PN"AB2"140;
"MGB_DATA1"
$PN"CC3"141;
"MGB_DQS_H5"
$PN"CF4"59;
"MGB_DQS_L9"
$PN"BW2"39;
"MG_RESET_L"
$PN"AT2"24;
"MG_ALERT_L"
$PN"AR2"12;
%"TAP"
"1","(-3425,6050)","0","mstr_standard","I170";
;
CDS_LIB"mstr_standard"
BODY_TYPE"PLUMBING"
HDL_TAP"TRUE";
"B \NAC \NWC"1;
"S \NAC"
BN"0"142;
%"TAP"
"1","(-3425,6000)","0","mstr_standard","I171";
;
CDS_LIB"mstr_standard"
BODY_TYPE"PLUMBING"
HDL_TAP"TRUE";
"B \NAC \NWC"1;
"S \NAC"
BN"1"157;
%"TAP"
"1","(-3425,5950)","0","mstr_standard","I172";
;
CDS_LIB"mstr_standard"
BODY_TYPE"PLUMBING"
HDL_TAP"TRUE";
"B \NAC \NWC"1;
"S \NAC"
BN"2"155;
%"TAP"
"1","(-3425,5900)","0","mstr_standard","I173";
;
CDS_LIB"mstr_standard"
BODY_TYPE"PLUMBING"
HDL_TAP"TRUE";
"B \NAC \NWC"1;
"S \NAC"
BN"3"153;
%"TAP"
"1","(-3425,5850)","0","mstr_standard","I174";
;
CDS_LIB"mstr_standard"
BODY_TYPE"PLUMBING"
HDL_TAP"TRUE";
"B \NAC \NWC"1;
"S \NAC"
BN"4"151;
%"TAP"
"1","(-3425,5800)","0","mstr_standard","I175";
;
CDS_LIB"mstr_standard"
BODY_TYPE"PLUMBING"
HDL_TAP"TRUE";
"B \NAC \NWC"1;
"S \NAC"
BN"5"149;
%"TAP"
"1","(-3425,5700)","0","mstr_standard","I176";
;
CDS_LIB"mstr_standard"
BODY_TYPE"PLUMBING"
HDL_TAP"TRUE";
"B \NAC \NWC"1;
"S \NAC"
BN"7"146;
%"TAP"
"1","(-3425,5750)","0","mstr_standard","I177";
;
CDS_LIB"mstr_standard"
BODY_TYPE"PLUMBING"
HDL_TAP"TRUE";
"B \NAC \NWC"1;
"S \NAC"
BN"6"147;
%"TAP"
"1","(-3425,5600)","0","mstr_standard","I178";
;
CDS_LIB"mstr_standard"
BODY_TYPE"PLUMBING"
HDL_TAP"TRUE";
"B \NAC \NWC"1;
"S \NAC"
BN"8"145;
%"TAP"
"1","(-3425,5550)","0","mstr_standard","I179";
;
CDS_LIB"mstr_standard"
BODY_TYPE"PLUMBING"
HDL_TAP"TRUE";
"B \NAC \NWC"1;
"S \NAC"
BN"9"144;
%"TAP"
"1","(-3425,5450)","0","mstr_standard","I180";
;
CDS_LIB"mstr_standard"
BODY_TYPE"PLUMBING"
HDL_TAP"TRUE";
"B \NAC \NWC"1;
"S \NAC"
BN"11"158;
%"TAP"
"1","(-3425,5500)","0","mstr_standard","I181";
;
CDS_LIB"mstr_standard"
BODY_TYPE"PLUMBING"
HDL_TAP"TRUE";
"B \NAC \NWC"1;
"S \NAC"
BN"10"143;
%"TAP"
"1","(-3425,5400)","0","mstr_standard","I182";
;
CDS_LIB"mstr_standard"
BODY_TYPE"PLUMBING"
HDL_TAP"TRUE";
"B \NAC \NWC"1;
"S \NAC"
BN"12"156;
%"TAP"
"1","(-3425,5350)","0","mstr_standard","I183";
;
CDS_LIB"mstr_standard"
BODY_TYPE"PLUMBING"
HDL_TAP"TRUE";
"B \NAC \NWC"1;
"S \NAC"
BN"13"154;
%"TAP"
"1","(-3425,5250)","0","mstr_standard","I184";
;
CDS_LIB"mstr_standard"
BODY_TYPE"PLUMBING"
HDL_TAP"TRUE";
"B \NAC \NWC"1;
"S \NAC"
BN"15"150;
%"TAP"
"1","(-3425,5300)","0","mstr_standard","I185";
;
CDS_LIB"mstr_standard"
BODY_TYPE"PLUMBING"
HDL_TAP"TRUE";
"B \NAC \NWC"1;
"S \NAC"
BN"14"152;
%"TAP"
"1","(-3425,5150)","0","mstr_standard","I186";
;
CDS_LIB"mstr_standard"
BODY_TYPE"PLUMBING"
HDL_TAP"TRUE";
"B \NAC \NWC"1;
"S \NAC"
BN"16"148;
%"TAP"
"1","(-3425,5100)","0","mstr_standard","I187";
;
CDS_LIB"mstr_standard"
BODY_TYPE"PLUMBING"
HDL_TAP"TRUE";
"B \NAC \NWC"1;
"S \NAC"
BN"17"131;
%"TAP"
"1","(-3425,5050)","0","mstr_standard","I188";
;
CDS_LIB"mstr_standard"
BODY_TYPE"PLUMBING"
HDL_TAP"TRUE";
"B \NAC \NWC"1;
"S \NAC"
BN"18"129;
%"TAP"
"1","(-3425,5000)","0","mstr_standard","I189";
;
CDS_LIB"mstr_standard"
BODY_TYPE"PLUMBING"
HDL_TAP"TRUE";
"B \NAC \NWC"1;
"S \NAC"
BN"19"128;
%"TAP"
"1","(-3425,4950)","0","mstr_standard","I190";
;
CDS_LIB"mstr_standard"
BODY_TYPE"PLUMBING"
HDL_TAP"TRUE";
"B \NAC \NWC"1;
"S \NAC"
BN"20"125;
%"TAP"
"1","(-3425,4900)","0","mstr_standard","I191";
;
CDS_LIB"mstr_standard"
BODY_TYPE"PLUMBING"
HDL_TAP"TRUE";
"B \NAC \NWC"1;
"S \NAC"
BN"21"123;
%"TAP"
"1","(-3425,4800)","0","mstr_standard","I192";
;
CDS_LIB"mstr_standard"
BODY_TYPE"PLUMBING"
HDL_TAP"TRUE";
"B \NAC \NWC"1;
"S \NAC"
BN"23"138;
%"TAP"
"1","(-3425,4850)","0","mstr_standard","I193";
;
CDS_LIB"mstr_standard"
BODY_TYPE"PLUMBING"
HDL_TAP"TRUE";
"B \NAC \NWC"1;
"S \NAC"
BN"22"140;
%"TAP"
"1","(-3425,4700)","0","mstr_standard","I194";
;
CDS_LIB"mstr_standard"
BODY_TYPE"PLUMBING"
HDL_TAP"TRUE";
"B \NAC \NWC"1;
"S \NAC"
BN"24"136;
%"TAP"
"1","(-3425,4650)","0","mstr_standard","I195";
;
CDS_LIB"mstr_standard"
BODY_TYPE"PLUMBING"
HDL_TAP"TRUE";
"B \NAC \NWC"1;
"S \NAC"
BN"25"135;
%"TAP"
"1","(-3425,4550)","0","mstr_standard","I196";
;
CDS_LIB"mstr_standard"
BODY_TYPE"PLUMBING"
HDL_TAP"TRUE";
"B \NAC \NWC"1;
"S \NAC"
BN"27"133;
%"TAP"
"1","(-3425,4600)","0","mstr_standard","I197";
;
CDS_LIB"mstr_standard"
BODY_TYPE"PLUMBING"
HDL_TAP"TRUE";
"B \NAC \NWC"1;
"S \NAC"
BN"26"134;
%"TAP"
"1","(-3425,4500)","0","mstr_standard","I198";
;
CDS_LIB"mstr_standard"
BODY_TYPE"PLUMBING"
HDL_TAP"TRUE";
"B \NAC \NWC"1;
"S \NAC"
BN"28"132;
%"TAP"
"1","(-3425,4450)","0","mstr_standard","I199";
;
CDS_LIB"mstr_standard"
BODY_TYPE"PLUMBING"
HDL_TAP"TRUE";
"B \NAC \NWC"1;
"S \NAC"
BN"29"130;
%"TAP"
"1","(-3425,4400)","0","mstr_standard","I200";
;
CDS_LIB"mstr_standard"
BODY_TYPE"PLUMBING"
HDL_TAP"TRUE";
"B \NAC \NWC"1;
"S \NAC"
BN"30"127;
%"TAP"
"1","(-3425,4250)","0","mstr_standard","I201";
;
CDS_LIB"mstr_standard"
BODY_TYPE"PLUMBING"
HDL_TAP"TRUE";
"B \NAC \NWC"2;
"S \NAC"
BN"0"124;
%"TAP"
"1","(-3425,4350)","0","mstr_standard","I202";
;
CDS_LIB"mstr_standard"
BODY_TYPE"PLUMBING"
HDL_TAP"TRUE";
"B \NAC \NWC"1;
"S \NAC"
BN"31"126;
%"TAP"
"1","(-3425,4200)","0","mstr_standard","I203";
;
CDS_LIB"mstr_standard"
BODY_TYPE"PLUMBING"
HDL_TAP"TRUE";
"B \NAC \NWC"2;
"S \NAC"
BN"1"141;
%"TAP"
"1","(-3425,4150)","0","mstr_standard","I204";
;
CDS_LIB"mstr_standard"
BODY_TYPE"PLUMBING"
HDL_TAP"TRUE";
"B \NAC \NWC"2;
"S \NAC"
BN"2"139;
%"TAP"
"1","(-3425,4100)","0","mstr_standard","I205";
;
CDS_LIB"mstr_standard"
BODY_TYPE"PLUMBING"
HDL_TAP"TRUE";
"B \NAC \NWC"2;
"S \NAC"
BN"3"137;
%"TAP"
"1","(-3425,4050)","0","mstr_standard","I207";
;
CDS_LIB"mstr_standard"
BODY_TYPE"PLUMBING"
HDL_TAP"TRUE";
"B \NAC \NWC"2;
"S \NAC"
BN"4"122;
%"TAP"
"1","(-3425,4000)","0","mstr_standard","I208";
;
CDS_LIB"mstr_standard"
BODY_TYPE"PLUMBING"
HDL_TAP"TRUE";
"B \NAC \NWC"2;
"S \NAC"
BN"5"120;
%"TAP"
"1","(-3425,3900)","0","mstr_standard","I209";
;
CDS_LIB"mstr_standard"
BODY_TYPE"PLUMBING"
HDL_TAP"TRUE";
"B \NAC \NWC"2;
"S \NAC"
BN"7"115;
%"TAP"
"1","(-3425,3950)","0","mstr_standard","I210";
;
CDS_LIB"mstr_standard"
BODY_TYPE"PLUMBING"
HDL_TAP"TRUE";
"B \NAC \NWC"2;
"S \NAC"
BN"6"117;
%"TAP"
"1","(-3425,3800)","0","mstr_standard","I211";
;
CDS_LIB"mstr_standard"
BODY_TYPE"PLUMBING"
HDL_TAP"TRUE";
"B \NAC \NWC"2;
"S \NAC"
BN"8"113;
%"TAP"
"1","(-3425,3750)","0","mstr_standard","I212";
;
CDS_LIB"mstr_standard"
BODY_TYPE"PLUMBING"
HDL_TAP"TRUE";
"B \NAC \NWC"2;
"S \NAC"
BN"9"111;
%"TAP"
"1","(-3425,3650)","0","mstr_standard","I213";
;
CDS_LIB"mstr_standard"
BODY_TYPE"PLUMBING"
HDL_TAP"TRUE";
"B \NAC \NWC"2;
"S \NAC"
BN"11"116;
%"TAP"
"1","(-3425,3700)","0","mstr_standard","I214";
;
CDS_LIB"mstr_standard"
BODY_TYPE"PLUMBING"
HDL_TAP"TRUE";
"B \NAC \NWC"2;
"S \NAC"
BN"10"118;
%"TAP"
"1","(-3425,3600)","0","mstr_standard","I215";
;
CDS_LIB"mstr_standard"
BODY_TYPE"PLUMBING"
HDL_TAP"TRUE";
"B \NAC \NWC"2;
"S \NAC"
BN"12"114;
%"TAP"
"1","(-3425,3550)","0","mstr_standard","I216";
;
CDS_LIB"mstr_standard"
BODY_TYPE"PLUMBING"
HDL_TAP"TRUE";
"B \NAC \NWC"2;
"S \NAC"
BN"13"112;
%"TAP"
"1","(-3425,3500)","0","mstr_standard","I217";
;
CDS_LIB"mstr_standard"
BODY_TYPE"PLUMBING"
HDL_TAP"TRUE";
"B \NAC \NWC"2;
"S \NAC"
BN"14"110;
%"TAP"
"1","(-3425,3350)","0","mstr_standard","I218";
;
CDS_LIB"mstr_standard"
BODY_TYPE"PLUMBING"
HDL_TAP"TRUE";
"B \NAC \NWC"2;
"S \NAC"
BN"16"108;
%"TAP"
"1","(-3425,3450)","0","mstr_standard","I219";
;
CDS_LIB"mstr_standard"
BODY_TYPE"PLUMBING"
HDL_TAP"TRUE";
"B \NAC \NWC"2;
"S \NAC"
BN"15"109;
%"TAP"
"1","(-3425,3300)","0","mstr_standard","I220";
;
CDS_LIB"mstr_standard"
BODY_TYPE"PLUMBING"
HDL_TAP"TRUE";
"B \NAC \NWC"2;
"S \NAC"
BN"17"107;
%"TAP"
"1","(-3425,3250)","0","mstr_standard","I221";
;
CDS_LIB"mstr_standard"
BODY_TYPE"PLUMBING"
HDL_TAP"TRUE";
"B \NAC \NWC"2;
"S \NAC"
BN"18"106;
%"TAP"
"1","(-3425,3200)","0","mstr_standard","I222";
;
CDS_LIB"mstr_standard"
BODY_TYPE"PLUMBING"
HDL_TAP"TRUE";
"B \NAC \NWC"2;
"S \NAC"
BN"19"105;
%"TAP"
"1","(-3425,3150)","0","mstr_standard","I223";
;
CDS_LIB"mstr_standard"
BODY_TYPE"PLUMBING"
HDL_TAP"TRUE";
"B \NAC \NWC"2;
"S \NAC"
BN"20"121;
%"TAP"
"1","(-3425,3100)","0","mstr_standard","I224";
;
CDS_LIB"mstr_standard"
BODY_TYPE"PLUMBING"
HDL_TAP"TRUE";
"B \NAC \NWC"2;
"S \NAC"
BN"21"119;
%"TAP"
"1","(-3425,3050)","0","mstr_standard","I225";
;
CDS_LIB"mstr_standard"
BODY_TYPE"PLUMBING"
HDL_TAP"TRUE";
"B \NAC \NWC"2;
"S \NAC"
BN"22"96;
%"TAP"
"1","(-3425,3000)","0","mstr_standard","I226";
;
CDS_LIB"mstr_standard"
BODY_TYPE"PLUMBING"
HDL_TAP"TRUE";
"B \NAC \NWC"2;
"S \NAC"
BN"23"95;
%"TAP"
"1","(-3425,2900)","0","mstr_standard","I227";
;
CDS_LIB"mstr_standard"
BODY_TYPE"PLUMBING"
HDL_TAP"TRUE";
"B \NAC \NWC"2;
"S \NAC"
BN"24"94;
%"TAP"
"1","(-3425,2850)","0","mstr_standard","I228";
;
CDS_LIB"mstr_standard"
BODY_TYPE"PLUMBING"
HDL_TAP"TRUE";
"B \NAC \NWC"2;
"S \NAC"
BN"25"93;
%"TAP"
"1","(-3425,2800)","0","mstr_standard","I229";
;
CDS_LIB"mstr_standard"
BODY_TYPE"PLUMBING"
HDL_TAP"TRUE";
"B \NAC \NWC"2;
"S \NAC"
BN"26"92;
%"TAP"
"1","(-3425,2750)","0","mstr_standard","I230";
;
CDS_LIB"mstr_standard"
BODY_TYPE"PLUMBING"
HDL_TAP"TRUE";
"B \NAC \NWC"2;
"S \NAC"
BN"27"91;
%"TAP"
"1","(-3425,2700)","0","mstr_standard","I231";
;
CDS_LIB"mstr_standard"
BODY_TYPE"PLUMBING"
HDL_TAP"TRUE";
"B \NAC \NWC"2;
"S \NAC"
BN"28"90;
%"TAP"
"1","(-3425,2650)","0","mstr_standard","I232";
;
CDS_LIB"mstr_standard"
BODY_TYPE"PLUMBING"
HDL_TAP"TRUE";
"B \NAC \NWC"2;
"S \NAC"
BN"29"89;
%"TAP"
"1","(-3425,2600)","0","mstr_standard","I233";
;
CDS_LIB"mstr_standard"
BODY_TYPE"PLUMBING"
HDL_TAP"TRUE";
"B \NAC \NWC"2;
"S \NAC"
BN"30"101;
%"TAP"
"1","(-3425,2450)","0","mstr_standard","I234";
;
CDS_LIB"mstr_standard"
BODY_TYPE"PLUMBING"
HDL_TAP"TRUE";
"B \NAC \NWC"3;
"S \NAC"
BN"0"88;
%"TAP"
"1","(-3425,2550)","0","mstr_standard","I235";
;
CDS_LIB"mstr_standard"
BODY_TYPE"PLUMBING"
HDL_TAP"TRUE";
"B \NAC \NWC"2;
"S \NAC"
BN"31"99;
%"TAP"
"1","(-3425,2400)","0","mstr_standard","I236";
;
CDS_LIB"mstr_standard"
BODY_TYPE"PLUMBING"
HDL_TAP"TRUE";
"B \NAC \NWC"3;
"S \NAC"
BN"1"87;
%"TAP"
"1","(-3425,2350)","0","mstr_standard","I237";
;
CDS_LIB"mstr_standard"
BODY_TYPE"PLUMBING"
HDL_TAP"TRUE";
"B \NAC \NWC"3;
"S \NAC"
BN"2"104;
%"TAP"
"1","(-3425,2250)","0","mstr_standard","I238";
;
CDS_LIB"mstr_standard"
BODY_TYPE"PLUMBING"
HDL_TAP"TRUE";
"B \NAC \NWC"3;
"S \NAC"
BN"4"102;
%"TAP"
"1","(-3425,2300)","0","mstr_standard","I239";
;
CDS_LIB"mstr_standard"
BODY_TYPE"PLUMBING"
HDL_TAP"TRUE";
"B \NAC \NWC"3;
"S \NAC"
BN"3"103;
%"TAP"
"1","(-3425,2200)","0","mstr_standard","I240";
;
CDS_LIB"mstr_standard"
BODY_TYPE"PLUMBING"
HDL_TAP"TRUE";
"B \NAC \NWC"3;
"S \NAC"
BN"5"100;
%"TAP"
"1","(-3425,2100)","0","mstr_standard","I241";
;
CDS_LIB"mstr_standard"
BODY_TYPE"PLUMBING"
HDL_TAP"TRUE";
"B \NAC \NWC"3;
"S \NAC"
BN"7"97;
%"TAP"
"1","(-3425,2150)","0","mstr_standard","I242";
;
CDS_LIB"mstr_standard"
BODY_TYPE"PLUMBING"
HDL_TAP"TRUE";
"B \NAC \NWC"3;
"S \NAC"
BN"6"98;
%"TAP"
"1","(-3425,2000)","0","mstr_standard","I244";
;
CDS_LIB"mstr_standard"
BODY_TYPE"PLUMBING"
HDL_TAP"TRUE";
"B \NAC \NWC"4;
"S \NAC"
BN"0"86;
%"TAP"
"1","(-3425,1950)","0","mstr_standard","I245";
;
CDS_LIB"mstr_standard"
BODY_TYPE"PLUMBING"
HDL_TAP"TRUE";
"B \NAC \NWC"4;
"S \NAC"
BN"1"85;
%"TAP"
"1","(-3425,1900)","0","mstr_standard","I246";
;
CDS_LIB"mstr_standard"
BODY_TYPE"PLUMBING"
HDL_TAP"TRUE";
"B \NAC \NWC"4;
"S \NAC"
BN"2"84;
%"TAP"
"1","(-3425,1850)","0","mstr_standard","I247";
;
CDS_LIB"mstr_standard"
BODY_TYPE"PLUMBING"
HDL_TAP"TRUE";
"B \NAC \NWC"4;
"S \NAC"
BN"3"83;
%"TAP"
"1","(-3425,1800)","0","mstr_standard","I248";
;
CDS_LIB"mstr_standard"
BODY_TYPE"PLUMBING"
HDL_TAP"TRUE";
"B \NAC \NWC"4;
"S \NAC"
BN"4"82;
%"TAP"
"1","(-3425,1750)","0","mstr_standard","I249";
;
CDS_LIB"mstr_standard"
BODY_TYPE"PLUMBING"
HDL_TAP"TRUE";
"B \NAC \NWC"4;
"S \NAC"
BN"5"81;
%"TAP"
"1","(-3425,1700)","0","mstr_standard","I250";
;
CDS_LIB"mstr_standard"
BODY_TYPE"PLUMBING"
HDL_TAP"TRUE";
"B \NAC \NWC"4;
"S \NAC"
BN"6"80;
%"TAP"
"1","(-3425,1650)","0","mstr_standard","I251";
;
CDS_LIB"mstr_standard"
BODY_TYPE"PLUMBING"
HDL_TAP"TRUE";
"B \NAC \NWC"4;
"S \NAC"
BN"7"79;
%"TAP"
"1","(-5850,6050)","2","mstr_standard","I252";
;
CDS_LIB"mstr_standard"
BODY_TYPE"PLUMBING"
HDL_TAP"TRUE";
"B \NAC \NWC"6;
"S \NAC"
BN"0"73;
%"TAP"
"1","(-5850,5950)","2","mstr_standard","I253";
;
CDS_LIB"mstr_standard"
BODY_TYPE"PLUMBING"
HDL_TAP"TRUE";
"B \NAC \NWC"6;
"S \NAC"
BN"1"71;
%"TAP"
"1","(-5850,5850)","2","mstr_standard","I254";
;
CDS_LIB"mstr_standard"
BODY_TYPE"PLUMBING"
HDL_TAP"TRUE";
"B \NAC \NWC"6;
"S \NAC"
BN"2"69;
%"TAP"
"1","(-5850,5750)","2","mstr_standard","I255";
;
CDS_LIB"mstr_standard"
BODY_TYPE"PLUMBING"
HDL_TAP"TRUE";
"B \NAC \NWC"6;
"S \NAC"
BN"3"67;
%"TAP"
"1","(-5850,5650)","2","mstr_standard","I256";
;
CDS_LIB"mstr_standard"
BODY_TYPE"PLUMBING"
HDL_TAP"TRUE";
"B \NAC \NWC"6;
"S \NAC"
BN"4"65;
%"TAP"
"1","(-6050,6000)","2","mstr_standard","I257";
;
CDS_LIB"mstr_standard"
BODY_TYPE"PLUMBING"
HDL_TAP"TRUE";
"B \NAC \NWC"5;
"S \NAC"
BN"0"78;
%"TAP"
"1","(-6050,5900)","2","mstr_standard","I258";
;
CDS_LIB"mstr_standard"
BODY_TYPE"PLUMBING"
HDL_TAP"TRUE";
"B \NAC \NWC"5;
"S \NAC"
BN"1"77;
%"TAP"
"1","(-6050,5800)","2","mstr_standard","I259";
;
CDS_LIB"mstr_standard"
BODY_TYPE"PLUMBING"
HDL_TAP"TRUE";
"B \NAC \NWC"5;
"S \NAC"
BN"2"76;
%"TAP"
"1","(-6050,5700)","2","mstr_standard","I260";
;
CDS_LIB"mstr_standard"
BODY_TYPE"PLUMBING"
HDL_TAP"TRUE";
"B \NAC \NWC"5;
"S \NAC"
BN"3"75;
%"TAP"
"1","(-5850,5450)","2","mstr_standard","I261";
;
CDS_LIB"mstr_standard"
BODY_TYPE"PLUMBING"
HDL_TAP"TRUE";
"B \NAC \NWC"6;
"S \NAC"
BN"6"63;
%"TAP"
"1","(-5850,5550)","2","mstr_standard","I262";
;
CDS_LIB"mstr_standard"
BODY_TYPE"PLUMBING"
HDL_TAP"TRUE";
"B \NAC \NWC"6;
"S \NAC"
BN"5"64;
%"TAP"
"1","(-5850,5350)","2","mstr_standard","I263";
;
CDS_LIB"mstr_standard"
BODY_TYPE"PLUMBING"
HDL_TAP"TRUE";
"B \NAC \NWC"6;
"S \NAC"
BN"7"62;
%"TAP"
"1","(-5850,5250)","2","mstr_standard","I264";
;
CDS_LIB"mstr_standard"
BODY_TYPE"PLUMBING"
HDL_TAP"TRUE";
"B \NAC \NWC"6;
"S \NAC"
BN"8"61;
%"TAP"
"1","(-5850,5150)","2","mstr_standard","I265";
;
CDS_LIB"mstr_standard"
BODY_TYPE"PLUMBING"
HDL_TAP"TRUE";
"B \NAC \NWC"6;
"S \NAC"
BN"9"60;
%"TAP"
"1","(-6050,5600)","2","mstr_standard","I266";
;
CDS_LIB"mstr_standard"
BODY_TYPE"PLUMBING"
HDL_TAP"TRUE";
"B \NAC \NWC"5;
"S \NAC"
BN"4"74;
%"TAP"
"1","(-6050,5500)","2","mstr_standard","I267";
;
CDS_LIB"mstr_standard"
BODY_TYPE"PLUMBING"
HDL_TAP"TRUE";
"B \NAC \NWC"5;
"S \NAC"
BN"5"72;
%"TAP"
"1","(-6050,5400)","2","mstr_standard","I268";
;
CDS_LIB"mstr_standard"
BODY_TYPE"PLUMBING"
HDL_TAP"TRUE";
"B \NAC \NWC"5;
"S \NAC"
BN"6"70;
%"TAP"
"1","(-6050,5300)","2","mstr_standard","I269";
;
CDS_LIB"mstr_standard"
BODY_TYPE"PLUMBING"
HDL_TAP"TRUE";
"B \NAC \NWC"5;
"S \NAC"
BN"7"68;
%"TAP"
"1","(-6050,5200)","2","mstr_standard","I270";
;
CDS_LIB"mstr_standard"
BODY_TYPE"PLUMBING"
HDL_TAP"TRUE";
"B \NAC \NWC"5;
"S \NAC"
BN"8"66;
%"TAP"
"1","(-5850,5000)","2","mstr_standard","I271";
;
CDS_LIB"mstr_standard"
BODY_TYPE"PLUMBING"
HDL_TAP"TRUE";
"B \NAC \NWC"7;
"S \NAC"
BN"0"49;
%"TAP"
"1","(-5850,4900)","2","mstr_standard","I272";
;
CDS_LIB"mstr_standard"
BODY_TYPE"PLUMBING"
HDL_TAP"TRUE";
"B \NAC \NWC"7;
"S \NAC"
BN"1"47;
%"TAP"
"1","(-5850,4800)","2","mstr_standard","I273";
;
CDS_LIB"mstr_standard"
BODY_TYPE"PLUMBING"
HDL_TAP"TRUE";
"B \NAC \NWC"7;
"S \NAC"
BN"2"45;
%"TAP"
"1","(-5850,4700)","2","mstr_standard","I274";
;
CDS_LIB"mstr_standard"
BODY_TYPE"PLUMBING"
HDL_TAP"TRUE";
"B \NAC \NWC"7;
"S \NAC"
BN"3"43;
%"TAP"
"1","(-6050,5100)","2","mstr_standard","I275";
;
CDS_LIB"mstr_standard"
BODY_TYPE"PLUMBING"
HDL_TAP"TRUE";
"B \NAC \NWC"5;
"S \NAC"
BN"9"51;
%"TAP"
"1","(-6050,4950)","2","mstr_standard","I276";
;
CDS_LIB"mstr_standard"
BODY_TYPE"PLUMBING"
HDL_TAP"TRUE";
"B \NAC \NWC"8;
"S \NAC"
BN"0"55;
%"TAP"
"1","(-6050,4850)","2","mstr_standard","I277";
;
CDS_LIB"mstr_standard"
BODY_TYPE"PLUMBING"
HDL_TAP"TRUE";
"B \NAC \NWC"8;
"S \NAC"
BN"1"54;
%"TAP"
"1","(-6050,4750)","2","mstr_standard","I278";
;
CDS_LIB"mstr_standard"
BODY_TYPE"PLUMBING"
HDL_TAP"TRUE";
"B \NAC \NWC"8;
"S \NAC"
BN"2"53;
%"TAP"
"1","(-6050,4650)","2","mstr_standard","I279";
;
CDS_LIB"mstr_standard"
BODY_TYPE"PLUMBING"
HDL_TAP"TRUE";
"B \NAC \NWC"8;
"S \NAC"
BN"3"52;
%"TAP"
"1","(-5850,4600)","2","mstr_standard","I280";
;
CDS_LIB"mstr_standard"
BODY_TYPE"PLUMBING"
HDL_TAP"TRUE";
"B \NAC \NWC"7;
"S \NAC"
BN"4"41;
%"TAP"
"1","(-5850,4400)","2","mstr_standard","I281";
;
CDS_LIB"mstr_standard"
BODY_TYPE"PLUMBING"
HDL_TAP"TRUE";
"B \NAC \NWC"7;
"S \NAC"
BN"6"58;
%"TAP"
"1","(-5850,4500)","2","mstr_standard","I282";
;
CDS_LIB"mstr_standard"
BODY_TYPE"PLUMBING"
HDL_TAP"TRUE";
"B \NAC \NWC"7;
"S \NAC"
BN"5"59;
%"TAP"
"1","(-5850,4300)","2","mstr_standard","I283";
;
CDS_LIB"mstr_standard"
BODY_TYPE"PLUMBING"
HDL_TAP"TRUE";
"B \NAC \NWC"7;
"S \NAC"
BN"7"57;
%"TAP"
"1","(-5850,4200)","2","mstr_standard","I284";
;
CDS_LIB"mstr_standard"
BODY_TYPE"PLUMBING"
HDL_TAP"TRUE";
"B \NAC \NWC"7;
"S \NAC"
BN"8"56;
%"TAP"
"1","(-5850,4100)","2","mstr_standard","I285";
;
CDS_LIB"mstr_standard"
BODY_TYPE"PLUMBING"
HDL_TAP"TRUE";
"B \NAC \NWC"7;
"S \NAC"
BN"9"40;
%"TAP"
"1","(-6050,4550)","2","mstr_standard","I286";
;
CDS_LIB"mstr_standard"
BODY_TYPE"PLUMBING"
HDL_TAP"TRUE";
"B \NAC \NWC"8;
"S \NAC"
BN"4"50;
%"TAP"
"1","(-6050,4450)","2","mstr_standard","I287";
;
CDS_LIB"mstr_standard"
BODY_TYPE"PLUMBING"
HDL_TAP"TRUE";
"B \NAC \NWC"8;
"S \NAC"
BN"5"48;
%"TAP"
"1","(-6050,4250)","2","mstr_standard","I288";
;
CDS_LIB"mstr_standard"
BODY_TYPE"PLUMBING"
HDL_TAP"TRUE";
"B \NAC \NWC"8;
"S \NAC"
BN"7"44;
%"TAP"
"1","(-6050,4350)","2","mstr_standard","I289";
;
CDS_LIB"mstr_standard"
BODY_TYPE"PLUMBING"
HDL_TAP"TRUE";
"B \NAC \NWC"8;
"S \NAC"
BN"6"46;
%"TAP"
"1","(-6050,4150)","2","mstr_standard","I290";
;
CDS_LIB"mstr_standard"
BODY_TYPE"PLUMBING"
HDL_TAP"TRUE";
"B \NAC \NWC"8;
"S \NAC"
BN"8"42;
%"TAP"
"1","(-6050,4050)","2","mstr_standard","I295";
;
CDS_LIB"mstr_standard"
BODY_TYPE"PLUMBING"
HDL_TAP"TRUE";
"B \NAC \NWC"8;
"S \NAC"
BN"9"39;
%"TAP"
"1","(-6050,3900)","2","mstr_standard","I296";
;
CDS_LIB"mstr_standard"
BODY_TYPE"PLUMBING"
HDL_TAP"TRUE";
"B \NAC \NWC"9;
"S \NAC"
BN"0"38;
%"TAP"
"1","(-6050,3850)","2","mstr_standard","I297";
;
CDS_LIB"mstr_standard"
BODY_TYPE"PLUMBING"
HDL_TAP"TRUE";
"B \NAC \NWC"9;
"S \NAC"
BN"1"36;
%"TAP"
"1","(-6050,3800)","2","mstr_standard","I298";
;
CDS_LIB"mstr_standard"
BODY_TYPE"PLUMBING"
HDL_TAP"TRUE";
"B \NAC \NWC"9;
"S \NAC"
BN"2"34;
%"TAP"
"1","(-6050,3750)","2","mstr_standard","I299";
;
CDS_LIB"mstr_standard"
BODY_TYPE"PLUMBING"
HDL_TAP"TRUE";
"B \NAC \NWC"9;
"S \NAC"
BN"3"32;
%"TAP"
"1","(-6050,3700)","2","mstr_standard","I300";
;
CDS_LIB"mstr_standard"
BODY_TYPE"PLUMBING"
HDL_TAP"TRUE";
"B \NAC \NWC"9;
"S \NAC"
BN"4"30;
%"TAP"
"1","(-6050,3650)","2","mstr_standard","I301";
;
CDS_LIB"mstr_standard"
BODY_TYPE"PLUMBING"
HDL_TAP"TRUE";
"B \NAC \NWC"9;
"S \NAC"
BN"5"28;
%"TAP"
"1","(-6050,3600)","2","mstr_standard","I302";
;
CDS_LIB"mstr_standard"
BODY_TYPE"PLUMBING"
HDL_TAP"TRUE";
"B \NAC \NWC"9;
"S \NAC"
BN"6"26;
%"TAP"
"1","(-6050,3500)","2","mstr_standard","I303";
;
CDS_LIB"mstr_standard"
BODY_TYPE"PLUMBING"
HDL_TAP"TRUE";
"B \NAC \NWC"10;
"S \NAC"
BN"0"37;
%"TAP"
"1","(-6050,3450)","2","mstr_standard","I304";
;
CDS_LIB"mstr_standard"
BODY_TYPE"PLUMBING"
HDL_TAP"TRUE";
"B \NAC \NWC"10;
"S \NAC"
BN"1"35;
%"TAP"
"1","(-6050,3400)","2","mstr_standard","I305";
;
CDS_LIB"mstr_standard"
BODY_TYPE"PLUMBING"
HDL_TAP"TRUE";
"B \NAC \NWC"10;
"S \NAC"
BN"2"33;
%"TAP"
"1","(-6050,3350)","2","mstr_standard","I306";
;
CDS_LIB"mstr_standard"
BODY_TYPE"PLUMBING"
HDL_TAP"TRUE";
"B \NAC \NWC"10;
"S \NAC"
BN"3"31;
%"TAP"
"1","(-6050,3300)","2","mstr_standard","I307";
;
CDS_LIB"mstr_standard"
BODY_TYPE"PLUMBING"
HDL_TAP"TRUE";
"B \NAC \NWC"10;
"S \NAC"
BN"4"29;
%"TAP"
"1","(-6050,3250)","2","mstr_standard","I308";
;
CDS_LIB"mstr_standard"
BODY_TYPE"PLUMBING"
HDL_TAP"TRUE";
"B \NAC \NWC"10;
"S \NAC"
BN"5"27;
%"TAP"
"1","(-6050,3200)","2","mstr_standard","I309";
;
CDS_LIB"mstr_standard"
BODY_TYPE"PLUMBING"
HDL_TAP"TRUE";
"B \NAC \NWC"10;
"S \NAC"
BN"6"25;
%"Q_RES"
"1","(-6975,2200)","0","pure_quanta","I323";
;
LOCATION"R381"
$SEC"1"
CDS_SEC"1"
PACK_TYPE"0402LF"
TOLERANCE"1%"
VALUE"15"
MATERIAL"CHIP"
WATTAGE"1/16W"
CDS_LIB"pure_quanta"
PART_NUMBER"CS01502FB03";
"B"
$PN"2"12;
"A"
$PN"1"11;
END.
